# BASEBOARD_FAB2 (Tioga Pass) — schematic parts with pin connectivity, parts 4676–4676 of 4751; source: Cadence DE-HDL packaged netlist (pstxprt.dat, pstxnet.dat, pstchip.dat)

U7C1  LBG_CORE_QAT_EXT_D  IC  pkg BGA1  page 114  (pins 313-624 of 1310)
  AP34  VCCPRIM_AVID(9)  POWER  = PVNN_PCH_STBY
  AP36  VCCPRIM_AVID(8)  POWER  = PVNN_PCH_STBY
  AP37  VCCPRIM_AVID(7)  POWER  = PVNN_PCH_STBY
  AP39  VCCPRIM_AVID(6)  POWER  = PVNN_PCH_STBY
  AP41  VSS(195)  GROUND  = GND
  AP43  VCCMPHY_1P05(8)  POWER  = P1V05_PCH_STBY
  AP45  VCCMPHY_1P05(7)  POWER  = P1V05_PCH_STBY
  AP46  VSS(194)  GROUND  = GND
  AP48  VCCP_HSIOPLL_1P05(3)  POWER  = P1V05_PCH_STBY_WM26_PLL
  AP52  VSS(193)  GROUND  = GND
  AP56  JTAG_TDO  BI  = XDP_TDO
  AP59  PCIE18_UP6_SATA6_RXN  BI  = SATA6G_PCH_PCIE_UP_SATA_RXN<6>
  AP63  PCIE15_UP3_SATA3_RXN  BI  = SATA6G_PCH_PCIE_UP_SATA_RXN<3>
  AP66  VSS(192)  GROUND  = GND
  AP69  RSVD(47)  UNSPEC  = TP_PCH_RSVD47
  AP71  RSVD(48)  UNSPEC  = TP_PCH_RSVD48
  AR1  GPP_H3_SRCCLKREQ9_N  BI  = NC
  AR3  GPP_H8_SRCCLKREQ14_N  BI  = NC
  AR5  VSS(191)  GROUND  = GND
  AR9  GPP_F11_SATA_SLOAD  BI  = SGPIO_PCH_SATA_LOAD
  AR13  GPP_F15_USB2_OC4_N  BI  = FM_FORCE_ADR_N
  AR17  GPP_F21_LAN_SMBALRT_N  BI  = IRQ_PCH_NIC_ALERT_N
  AR20  GPP_F9_SATA_DEVSLP7  BI  = JTAG_PCH_PLD_TDO
  AR24  VCCPSPI  POWER  = P3V3_STBY
  AR50  VSS(190)  GROUND  = GND
  AR54  ITP_PMODE  BI  = XDP_ITP_PMODE
  AR58  VSS(189)  GROUND  = GND
  AR61  PCIE12_UP0_SATA0_RXN  BI  = SATA6G_PCH_PCIE_UP_SATA_RXN<0>
  AR65  VSS(188)  GROUND  = GND
  AR68  VSS(187)  GROUND  = GND
  AR70  VSS(186)  GROUND  = GND
  AR72  VSS(185)  GROUND  = GND
  AT2  GPP_H4_SRCCLKREQ10_N  BI  = NC
  AT4  GPP_H0_SRCCLKREQ6_N  BI  = FM_UARTSW_LSB_N
  AT7  VSS(184)  GROUND  = GND
  AT11  VSS(183)  GROUND  = GND
  AT15  VSS(182)  GROUND  = GND
  AT18  VSS(181)  GROUND  = GND
  AT22  VSS(180)  GROUND  = GND
  AT26  VSS(179)  GROUND  = GND
  AT27  RSVD(59)  UNSPEC  = TP_PCH_RSVD59
  AT29  VCCPGPP_1P8(2)  POWER  = P1V8_PCH_STBY
  AT30  VSS(178)  GROUND  = GND
  AT32  VCCPRIM_AVID(5)  POWER  = PVNN_PCH_STBY
  AT34  VCCPRIM_AVID(4)  POWER  = PVNN_PCH_STBY
  AT36  VCCPRIM_AVID(3)  POWER  = PVNN_PCH_STBY
  AT37  VSS(451)  GROUND  = GND
  AT39  VCCPRIM_1P05(4)  POWER  = P1V05_PCH_STBY
  AT41  VSS(177)  GROUND  = GND
  AT43  VCCMPHY_1P05(6)  POWER  = P1V05_PCH_STBY
  AT45  VCCMPHY_1P05(5)  POWER  = P1V05_PCH_STBY
  AT46  VSS(176)  GROUND  = GND
  AT48  VCCP_HSIOPLLUNF_1P05  POWER  = P1V05_PCH_STBY
  AT52  GPP_E5_SATA_DEVSLP1  BI  = FM_CPU_MSMI_LVT3_N
  AT56  CPU_TRST_N  BI  = XDP_TRST_N
  AT59  VSS(175)  GROUND  = GND
  AT63  PCIE12_UP0_SATA0_RXP  BI  = SATA6G_PCH_PCIE_UP_SATA_RXP<0>
  AT66  PCIE11_SSATA5_GBE_RXN  BI  = NC
  AT69  RSVD(6)  UNSPEC  = TP_PCH_RSVD6
  AT71  RSVD(22)  UNSPEC  = TP_PCH_RSVD22
  AU9  GPP_F19_LAN_SMBCLK  BI  = SMB_LAN_STBY_LVC3_SCL_R2
  AU13  GPP_F16_USB2_OC5_N  BI  = FM_IE_DISABLE_N
  AU17  GPP_F23_SSATA_SLOAD  BI  = SGPIO_PCH_SSATA_LOAD
  AU20  GPP_F20_LAN_SMBDATA  BI  = SMB_LAN_STBY_LVC3_SDA_R2
  AU24  VCCPGPPK  POWER  = P3V3_STBY
  AU26  VSS(174)  GROUND  = GND
  AU27  VCCPGPPF  POWER  = P3V3_STBY
  AU29  VCCPGPP_1P8(0)  POWER  = P1V8_PCH_STBY
  AU30  VSS(173)  GROUND  = GND
  AU32  VCCPRIM_AVID(2)  POWER  = PVNN_PCH_STBY
  AU34  VCCPRIM_AVID(1)  POWER  = PVNN_PCH_STBY
  AU36  VCCPRIM_AVID(0)  POWER  = PVNN_PCH_STBY
  AU37  VCCPRIM_1P05(3)  POWER  = P1V05_PCH_STBY
  AU39  VCCPRIM_1P05(2)  POWER  = P1V05_PCH_STBY
  AU41  VSS(171)  GROUND  = GND
  AU43  VCCMPHY_1P05(4)  POWER  = P1V05_PCH_STBY
  AU45  VCCMPHY_1P05(3)  POWER  = P1V05_PCH_STBY
  AU46  VSS(170)  GROUND  = GND
  AU48  VCCP_HSIOPLL_1P05(2)  POWER  = P1V05_PCH_STBY_WM26_PLL
  AU50  VSS(169)  GROUND  = GND
  AU54  VSS(168)  GROUND  = GND
  AU58  GPP_E12_USB2_OC3_N  BI  = IRQ_UV_DETECT_N
  AU61  VSS(167)  GROUND  = GND
  AU65  PCIE10_SSATA4_RXP  BI  = NC
  AV1  GPP_H7_SRCCLKREQ13_N  BI  = NC
  AV3  GPP_H2_SRCCLKREQ8_N  BI  = NC
  AV5  VSS(166)  GROUND  = GND
  AV7  GPP_G14  BI  = FM_BOARD_SKU_ID2
  AV11  GPP_G9_FANPWM1_FAMPWM1IE  BI  = NC
  AV15  GPP_G1_FANTACH1_FANTACH1IE  BI  = NC
  AV18  GPP_G6_FANTACH6_FANTACH6IE  BI  = FM_CPU1_THERMTRIP_LATCH_LVT3_N
  AV22  VSS(165)  GROUND  = GND
  AV52  GPP_E4_SATA_DEVSLP0  BI  = FM_CPU_ERR2_LVT3_N
  AV56  GPP_E8_SATA_LED_N  BI  = LED_PCH_SATA_HDD_N
  AV59  VSS(164)  GROUND  = GND
  AV63  PCIE10_SSATA4_RXN  BI  = NC
  AV66  PCIE11_SSATA5_GBE_RXP  BI  = NC
  AV68  VSS(163)  GROUND  = GND
  AV70  USB3_10_PCIE3_GBE_RXP  BI  = P3E_PCH_M2_RX_DP<3>
  AV72  USB3_10_PCIE3_GBE_RXN  BI  = P3E_PCH_M2_RX_DN<3>
  AW2  GPP_H6_SRCCLKREQ12_N  BI  = NC
  AW4  GPP_H1_SRCCLKREQ7_N  BI  = FM_BACKUP_BIOS_SEL_N
  AW9  VSS(162)  GROUND  = GND
  AW13  VSS(161)  GROUND  = GND
  AW17  VSS(160)  GROUND  = GND
  AW20  GPP_G5_FANTACH5_FANTACH5IE  BI  = NC
  AW24  VCCPGPPA  POWER  = P3V3_STBY
  AW26  VSS(159)  GROUND  = GND
  AW27  VCCPGPP_1P8(5)  POWER  = P1V8_PCH_STBY
  AW29  VCCPGPP_1P8(1)  POWER  = P1V8_PCH_STBY
  AW30  VSS(158)  GROUND  = GND
  AW32  VSS(157)  GROUND  = GND
  AW34  VSS(156)  GROUND  = GND
  AW36  VSS(155)  GROUND  = GND
  AW37  VSS(154)  GROUND  = GND
  AW39  VSS(153)  GROUND  = GND
  AW41  VSS(152)  GROUND  = GND
  AW43  VCCMPHY_1P05(1)  POWER  = P1V05_PCH_STBY
  AW45  VCCMPHY_1P05(0)  POWER  = P1V05_PCH_STBY
  AW46  VSS(151)  GROUND  = GND
  AW48  VCCP_HSIOPLL_1P05(0)  POWER  = P1V05_PCH_STBY_WM26_PLL
  AW50  VSS(150)  GROUND  = GND
  AW54  GPP_E11_USB2_OC2_N  BI  = IRQ_BMC_PCH_SMI_LPC_N
  AW58  VSS(149)  GROUND  = GND
  AW61  VSS(148)  GROUND  = GND
  AW65  PCIE9_SSATA3_RXN  BI  = NC
  AW69  USB3_9_PCIE2_RXP  BI  = P3E_PCH_M2_RX_DP<2>
  AW71  USB3_9_PCIE2_RXN  BI  = P3E_PCH_M2_RX_DN<2>
  AY1  GPP_H13_SML3CLK_IE  BI  = NC
  AY3  GPP_H5_SRCCLKREQ11_N  BI  = NC
  AY5  VSS(147)  GROUND  = GND
  AY7  GPP_G3_FANTACH3_FANTACH3IE  BI  = NC
  AY11  GPP_G0_FANTACH0_FANTACH0IE  BI  = NC
  AY15  GPP_G7_FANTACH7_FANTACH7IE  BI  = NC
  AY18  GPP_G13  BI  = FM_BOARD_SKU_ID1
  AY22  VSS(146)  GROUND  = GND
  AY52  GPP_E1_SATAXPCIE1_SATAGP1  BI  = FM_CPU1_RC_ERROR_R1_N
  AY56  VSS(145)  GROUND  = GND
  AY59  PCIE7_SSATA1_RXN  BI  = SATA6G_S1_RX_DN
  AY63  VSS(144)  GROUND  = GND
  AY66  PCIE9_SSATA3_RXP  BI  = NC
  AY68  VSS(143)  GROUND  = GND
  AY70  USB3_8_PCIE1_RXP  BI  = P3E_PCH_M2_RX_DP<1>
  AY72  USB3_8_PCIE1_RXN  BI  = P3E_PCH_M2_RX_DN<1>
  B10  RSVD(17)  UNSPEC  = TP_PCH_RSVD17
  B12  VSS(442)  GROUND  = GND
  B14  GPD10_SLP_S5_N  BI  = FM_CPU0_RC_ERROR_R_N
  B16  GPD5_SLP_S4_N  BI  = FM_SLPS4_N
  B19  VSS(441)  GROUND  = GND
  B21  CLKOUT_SRCN(11)  BI  = CLK_100M_MEZZ4_DN
  B23  CLKOUT_SRCN(10)  BI  = CLK_100M_MEZZ3_DN
  B25  VSS(440)  GROUND  = GND
  B27  VSS(439)  GROUND  = GND
  B29  CLKOUT_PLAT0N  BI  = CLK_100M_BMC_PE_DN
  B31  CLKOUT_SRCP(8)  BI  = CLK_100M_MEZZ1_DP
  B33  CLKOUT_SRCP(6)  BI  = CLK_100M_PCH_SLOTX24_S4_DP
  B35  XTAL_IN  BI  = XTAL_PCH_48M_IN
  B38  CLKOUT_NSSCCAP1N  BI  = TP_CLK_100M_NSSCC1_DN
  B40  CLKOUT_PLAT1N  BI  = TP_CLK_100M_PLAT1_DN
  B42  DMI_RXP(0)  BI  = DMI_CPU0_PCH_TX_C_DP<0>
  B44  DMI_RXP(2)  BI  = DMI_CPU0_PCH_TX_C_DP<2>
  B47  VSS(438)  GROUND  = GND
  B49  PCIEUP_1_RXP  BI  = P3E_CPU0_PE1_PCH_TXP<1>
  B51  PCIEUP_3_RXP  BI  = P3E_CPU0_PE1_PCH_TXP<3>
  B53  PCIEUP_5_RXP  BI  = P3E_CPU0_PE1_PCH_TXP<5>
  B55  PCIEUP_7_RXP  BI  = P3E_CPU0_PE1_PCH_TXP<7>
  B58  PCIEUP_9_RXP  BI  = P3E_CPU0_PE1_PCH_C_TXN<9>
  B60  PCIEUP_11_RXP  BI  = P3E_CPU0_PE1_PCH_C_TXP<11>
  B62  PCIEUP_13_RXP  BI  = P3E_CPU0_PE1_PCH_C_TXN<13>
  B64  PCIEUP_15_RXP  BI  = P3E_CPU0_PE1_PCH_C_TXN<15>
  BA2  GPP_H21_SSATAXPCIE3_SSATAGP3  BI  = FM_BIOS_SMI_ACTIVE_N
  BA4  GPP_H10_SML2CLK_IE  BI  = SMB_VR_STBY_LVC3_SCL_R1
  BA9  GPP_G4_FANTACH4_FANTACH4IE  BI  = NC
  BA13  GPP_G23_SSATAXPCIE0_SSATAGP0  BI  = FM_UARTSW_MSB_N
  BA17  GPP_G20_SSATA_DEVSLP0  BI  = IRQ_FORCE_NM_THROTTLE_N
  BA20  GPP_G11_FANPWM3_FANPMW3IE  BI  = NC
  BA24  VCCPGPPH  POWER  = P3V3_STBY
  BA26  VCCPGPPG  POWER  = P3V3_STBY
  BA27  VCCP10GBE_HV_1P8(1)  POWER  = P1V8_PCH_STBY
  BA29  VCCP10GBE_HV_1P8(0)  POWER  = P1V8_PCH_STBY
  BA30  VCCP10GBE_LV_1P05(6)  POWER  = P1V05_PCH_STBY
  BA32  VCCP10GBE_LV_1P05(5)  POWER  = P1V05_PCH_STBY
  BA34  VCCP10GBE_LV_1P05(4)  POWER  = P1V05_PCH_STBY
  BA36  VCCP10GBE_LV_1P05(3)  POWER  = P1V05_PCH_STBY
  BA37  VCCP10GBE_LV_1P05(2)  POWER  = P1V05_PCH_STBY
  BA39  VCCP10GBEPLL_1P05(3)  POWER  = P1V05_PCH_STBY_KR_PLL
  BA41  VCCP10GBEPLL_1P05(2)  POWER  = P1V05_PCH_STBY_KR_PLL
  BA43  VCCPGPPD  POWER  = P3V3_STBY
  BA45  VCCP_3P3(1)  POWER  = P3V3_STBY
  BA46  VCCP_3P3(0)  POWER  = P3V3_STBY
  BA48  VCCPUSBDSW_3P3  POWER  = P3V3_STBY
  BA50  VSS(142)  GROUND  = GND
  BA54  VSS(141)  GROUND  = GND
  BA58  VSS(140)  GROUND  = GND
  BA61  PCIE7_SSATA1_RXP  BI  = SATA6G_S1_RX_DP
  BA65  PCIE8_SSATA2_GBE_RXN  BI  = NC
  BA69  USB3_7_PCIE0_RXP  BI  = P3E_PCH_RX_0_DP
  BA71  USB3_7_PCIE0_RXN  BI  = P3E_PCH_RX_0_DN
  BB1  GPP_H12_SML2ALERT_N_IE_N  BI  = FM_FLASH_ATTACH_CFG_STRAP
  BB3  GPP_H15_SML3ALERT_N_IE_N  BI  = PU_ADR_TIMER_HOLD_OFF_N
  BB5  VSS(139)  GROUND  = GND
  BB7  VSS(138)  GROUND  = GND
  BB11  VSS(137)  GROUND  = GND
  BB15  VSS(136)  GROUND  = GND
  BB18  VSS(135)  GROUND  = GND
  BB22  VSS(134)  GROUND  = GND
  BB26  VCCPGPPJ  POWER  = P3V3_STBY
  BB29  LAN_RBIAS_0  BI  = A_KR0_RBIAS
  BB33  VCCP10GBE_LV_1P05(1)  POWER  = P1V05_PCH_STBY
  BB37  VCCP10GBE_LV_1P05(0)  POWER  = P1V05_PCH_STBY
  BB40  VCCP10GBEPLL_1P05(1)  POWER  = P1V05_PCH_STBY_KR_PLL
  BB44  VSS(133)  GROUND  = GND
  BB48  VSS(452)  GROUND  = GND
  BB52  GPP_E6_SATA_DEVSLP2  BI  = IRQ_BMC_PCH_NMI_STBY_N
  BB56  PCIE_RCOMPP  BI  = A_PCIE_RCOMP_P
  BB59  VSS(132)  GROUND  = GND
  BB63  PCIE6_SSATA0_RXN  BI  = SATA6G_S0_RX_DN
  BB66  VSS(131)  GROUND  = GND
  BB68  VSS(130)  GROUND  = GND
  BB70  VSS(129)  GROUND  = GND
  BB72  VSS(128)  GROUND  = GND
  BC2  GPP_H14_SML3DATA_IE  BI  = NC
  BC4  GPP_H18_SML4ALERT_N_IE_N  BI  = FM_OC_DETECT_EN_N
  BC69  VSS(127)  GROUND  = GND
  BC71  VSS(126)  GROUND  = GND
  BD1  GPP_H11_SML2DATA_IE  BI  = SMB_VR_STBY_LVC3_SDA_R1
  BD3  GPP_H19_SSATAXPCIE1_SSATAGP1  BI  = FP_PWR_ID_LED_N
  BD5  VSS(121)  GROUND  = GND
  BD9  GPP_G17_ADR_COMPLETE  BI  = FM_ADR_COMPLETE_R1
  BD13  GPP_G12  BI  = FM_BOARD_SKU_ID0
  BD17  GPP_G16  BI  = FM_BOARD_SKU_ID4
  BD20  GPP_G22_SSATA_DEVSLP2  BI  = FM_CPU0_RC_EN
  BD24  VSS(125)  GROUND  = GND
  BD27  VSS(124)  GROUND  = GND
  BD31  VSS(123)  GROUND  = GND
  BD35  VSS(122)  GROUND  = GND
  BD38  VCCP10GBEPLL_1P05(0)  POWER  = P1V05_PCH_STBY_KR_PLL
  BD42  LAN_RBIAS_1  BI  = A_KR1_RBIAS
  BD46  VCCP_1P8(0)  POWER  = P1V8_PCH_STBY
  BD50  VSS(120)  GROUND  = GND
  BD54  VSS(119)  GROUND  = GND
  BD58  PCIE_RCOMPN  BI  = A_PCIE_RCOMP_N
  BD61  PCIE6_SSATA0_RXP  BI  = SATA6G_S0_RX_DP
  BD65  PCIE8_SSATA2_GBE_RXP  BI  = NC
  BD68  VSS(118)  GROUND  = GND
  BD70  USB3_6_RXP  BI  = TP_USB3_P06_RXP
  BD72  USB3_6_RXN  BI  = TP_USB3_P06_RXN
  BE2  GPP_H9_SRCCLKREQ15_N  BI  = NC
  BE4  GPP_H17_SML4DATA_IE  BI  = SMB_LAN_STBY_LVC3_SDA_R1
  BE7  GPP_G18_NMI_N  BI  = FM_NMI_EVENT_N
  BE11  GPP_G10_FANPWM2_FANPWM2IE  BI  = NC
  BE15  GPP_G19_SMI_N  BI  = FM_BIOS_SMI_ACTIVE_N
  BE18  GPP_G15  BI  = FM_BOARD_SKU_ID3
  BE22  GPP_G2_FANTACH2_FANTACH2IE  BI  = NC
  BE26  VCCPGPPB  POWER  = P3V3_STBY
  BE29  VSS(117)  GROUND  = GND
  BE33  VSS(116)  GROUND  = GND
  BE37  VSS(115)  GROUND  = GND
  BE40  VCCPGPPC  POWER  = P3V3_STBY
  BE44  VCCPGPPE  POWER  = P3V3_STBY
  BE48  VCCPRIM_1P05(1)  POWER  = P1V05_PCH_STBY
  BE52  GPP_E3_CPU_GP0  BI  = FM_CPLD_ADR_TRIGGER_R_N
  BE56  VSS(114)  GROUND  = GND
  BE59  VSS(113)  GROUND  = GND
  BE63  VSS(112)  GROUND  = GND
  BE66  VSS(111)  GROUND  = GND
  BE69  USB3_5_RXP  BI  = TP_USB3_P05_RXP
  BE71  USB3_5_RXN  BI  = TP_USB3_P05_RXN
  BF1  GPP_H16_SML4CLK_IE  BI  = SMB_LAN_STBY_LVC3_SCL_R1
  BF3  GPP_H20_SSATAXPCIE2_SSATAGP2  BI  = FM_BMC_NMI_N
  BF5  VSS(101)  GROUND  = GND
  BF9  VSS(95)  GROUND  = GND
  BF13  VSS(110)  GROUND  = GND
  BF17  VSS(109)  GROUND  = GND
  BF20  VSS(106)  GROUND  = GND
  BF24  VSS(105)  GROUND  = GND
  BF27  VSS(104)  GROUND  = GND
  BF31  LAN_RX_P0P  BI  = KR_P0_OCP_RX_C_DP
  BF35  LAN_RX_P3N  BI  = NC
  BF38  VSS(103)  GROUND  = GND
  BF42  VSS(102)  GROUND  = GND
  BF46  VCCPRIM_1P05(0)  POWER  = P1V05_PCH_STBY
  BF50  VSS(100)  GROUND  = GND
  BF54  VSS(108)  GROUND  = GND
  BF58  VSS(99)  GROUND  = GND
  BF61  VSS(98)  GROUND  = GND
  BF65  VSS(97)  GROUND  = GND
  BF68  VSS(96)  GROUND  = GND
  BF70  USB3_4_RXP  BI  = TP_USB3_P04_RXP
  BF72  USB3_4_RXN  BI  = TP_USB3_P04_RXN
  BG7  GPP_G21_SSATA_DEVSLP1  BI  = FM_SOL_UART_CH_SEL
  BG11  GPP_G8_FANPWM0_FANPWM0IE  BI  = NC
  BG15  GPP_B17  BI  = FM_PCH_PWRBTN_OUT_N
  BG18  GPP_B6_SRCCLKREQ1_N  BI  = IRQ_PVDDQ_GHJ_VRHOT_LVT3_N
  BG22  GPP_B16  BI  = IRQ_PCH_NIC_ALERT_N
  BG26  RSVD(27)  UNSPEC  = TP_PCH_RSVD27
  BG29  LAN_RX_P1N  BI  = KR_P1_OCP_RX_C_DN
  BG33  VSS(94)  GROUND  = GND
  BG37  LAN_RX_P2P  BI  = NC
  BG40  RSVD(42)  UNSPEC  = TP_PCH_RSVD42
  BG44  VSS(107)  GROUND  = GND
  BG48  VSS(93)  GROUND  = GND
  BG52  GPP_E2_SATAXPCIE2_SATAGP2  BI  = FM_POST_CARD_PRES_BMC_R1_N
  BG56  USB3_4_TXP  BI  = TP_USB3_P04_TXP
  BG59  VSS(92)  GROUND  = GND
  BG63  VSS(91)  GROUND  = GND
  BG66  PCIE4_GBE_TXN  BI  = P2E_SSB_BMC_TX_DN
  BH2  GPP_H22_SSATAXPCIE4_SSATAGP4  BI  = FM_PCH_BMC_THERMTRIP_N
  BH4  GPP_H23_SSATAXPCIE5_SSATAGP5  BI  = FM_SSATA_PCIE_M2_SEL
  BH9  GPP_B1_CORE_VID1  BI  = VID_PCH_CORE_PVNN_AUX_VID_1
  BH13  GPP_B14_SPKR  BI  = FM_BIOS_TOP_SWAP_SPKR
  BH17  GPP_B21  BI  = FM_FAST_PROCHOT_EN_N
